(kicad_pcb
	(version 20260206)
	(generator "pcbnew")
	(generator_version "10.0")
	(general
		(thickness 1.6)
		(legacy_teardrops no)
	)
	(paper "A4")
	(title_block
		(title "12092022_DA0F0TFB6D0_F0T_FAN_BOARD_MP5048_D_brd_v02_OCP.brd")
		(comment 1 "Grand Teton / footprints 798-804 of 924")
	)
	(layers
		(0 "F.Cu" signal "TOP")
		(4 "In1.Cu" signal "GND")
		(6 "In2.Cu" signal "IN1")
		(8 "In3.Cu" signal "IN2")
		(10 "In4.Cu" signal "GND1")
		(2 "B.Cu" signal "BOTTOM")
		(9 "F.Adhes" user "F.Adhesive")
		(11 "B.Adhes" user "B.Adhesive")
		(13 "F.Paste" user "Package Geometry/Pastemask Top")
		(15 "B.Paste" user "Package Geometry/Pastemask Bottom")
		(5 "F.SilkS" user "Ref Des/Silkscreen Top")
		(7 "B.SilkS" user "Ref Des/Silkscreen Bottom")
		(1 "F.Mask" user "Board Geometry/Soldermask Top")
		(3 "B.Mask" user "Board Geometry/Soldermask Bottom")
		(17 "Dwgs.User" user "User.Drawings")
		(19 "Cmts.User" user "User.Comments")
		(21 "Eco1.User" user "User.Eco1")
		(23 "Eco2.User" user "User.Eco2")
		(25 "Edge.Cuts" user "Board Geometry/Outline")
		(27 "Margin" user)
		(31 "F.CrtYd" user "Package Geometry/Place Bound Top")
		(29 "B.CrtYd" user "Package Geometry/Place Bound Bottom")
		(35 "F.Fab" user "Ref Des/Assembly Top")
		(33 "B.Fab" user "Ref Des/Assembly Bottom")
	)
	(footprint ""
		(layer "B.Cu")
		(at 36.195 -250.23699 -90)
		(property "Reference" "PR33"
			(at 0 0 90)
			(layer "B.SilkS")
			(hide yes)
			(effects
				(font
					(size 1.27 1.27)
				)
				(justify mirror)
			)
		)
		(property "Value" ""
			(at 0 0 90)
			(layer "B.Fab")
			(effects
				(font
					(size 1.27 1.27)
				)
				(justify mirror)
			)
		)
		(duplicate_pad_numbers_are_jumpers no)
		(fp_line
			(start -0.7874 0.4064)
			(end 0.7874 0.4064)
			(stroke
				(width 0.1524)
				(type default)
			)
			(layer "B.SilkS")
		)
		(fp_line
			(start 0.7874 0.4064)
			(end 0.7874 -0.4064)
			(stroke
				(width 0.1524)
				(type default)
			)
			(layer "B.SilkS")
		)
		(fp_line
			(start -0.7874 -0.4064)
			(end -0.7874 0.4064)
			(stroke
				(width 0.1524)
				(type default)
			)
			(layer "B.SilkS")
		)
		(fp_line
			(start 0.7874 -0.4064)
			(end -0.7874 -0.4064)
			(stroke
				(width 0.1524)
				(type default)
			)
			(layer "B.SilkS")
		)
		(fp_line
			(start -0.67945 0.3048)
			(end -0.120396 0.3048)
			(stroke
				(width 0.1)
				(type default)
			)
			(layer "B.Fab")
		)
		(fp_line
			(start -0.120396 0.3048)
			(end -0.120396 0.2794)
			(stroke
				(width 0.1)
				(type default)
			)
			(layer "B.Fab")
		)
		(fp_line
			(start 0.12065 0.3048)
			(end 0.67945 0.3048)
			(stroke
				(width 0.1)
				(type default)
			)
			(layer "B.Fab")
		)
		(fp_line
			(start 0.67945 0.3048)
			(end 0.67945 -0.305054)
			(stroke
				(width 0.1)
				(type default)
			)
			(layer "B.Fab")
		)
		(fp_line
			(start -0.120396 0.2794)
			(end 0.12065 0.2794)
			(stroke
				(width 0.1)
				(type default)
			)
			(layer "B.Fab")
		)
		(fp_line
			(start 0.12065 0.2794)
			(end 0.12065 0.3048)
			(stroke
				(width 0.1)
				(type default)
			)
			(layer "B.Fab")
		)
		(fp_line
			(start -0.12065 -0.2794)
			(end -0.12065 -0.3048)
			(stroke
				(width 0.1)
				(type default)
			)
			(layer "B.Fab")
		)
		(fp_line
			(start 0.12065 -0.2794)
			(end -0.12065 -0.2794)
			(stroke
				(width 0.1)
				(type default)
			)
			(layer "B.Fab")
		)
		(fp_line
			(start -0.67945 -0.3048)
			(end -0.67945 0.3048)
			(stroke
				(width 0.1)
				(type default)
			)
			(layer "B.Fab")
		)
		(fp_line
			(start -0.12065 -0.3048)
			(end -0.67945 -0.3048)
			(stroke
				(width 0.1)
				(type default)
			)
			(layer "B.Fab")
		)
		(fp_line
			(start 0.12065 -0.305054)
			(end 0.12065 -0.2794)
			(stroke
				(width 0.1)
				(type default)
			)
			(layer "B.Fab")
		)
		(fp_line
			(start 0.67945 -0.305054)
			(end 0.12065 -0.305054)
			(stroke
				(width 0.1)
				(type default)
			)
			(layer "B.Fab")
		)
		(pad "1" smd circle
			(at 0.40005 0 90)
			(size 0 0)
			(layers "B.Cu" "B.Mask" "B.Paste")
			(net "FAN_1_CLREF")
		)
		(pad "2" smd circle
			(at -0.40005 0 90)
			(size 0 0)
			(layers "B.Cu" "B.Mask" "B.Paste")
			(net "GND")
		)
	)
	(footprint ""
		(layer "B.Cu")
		(at 17.653 -128.524 180)
		(property "Reference" "R5435"
			(at 0 0 0)
			(layer "B.SilkS")
			(hide yes)
			(effects
				(font
					(size 1.27 1.27)
				)
				(justify mirror)
			)
		)
		(property "Value" ""
			(at 0 0 0)
			(layer "B.Fab")
			(effects
				(font
					(size 1.27 1.27)
				)
				(justify mirror)
			)
		)
		(duplicate_pad_numbers_are_jumpers no)
		(fp_line
			(start 0.7874 0.4064)
			(end 0.7874 -0.4064)
			(stroke
				(width 0.1524)
				(type default)
			)
			(layer "B.SilkS")
		)
		(fp_line
			(start 0.7874 -0.4064)
			(end -0.7874 -0.4064)
			(stroke
				(width 0.1524)
				(type default)
			)
			(layer "B.SilkS")
		)
		(fp_line
			(start -0.7874 0.4064)
			(end 0.7874 0.4064)
			(stroke
				(width 0.1524)
				(type default)
			)
			(layer "B.SilkS")
		)
		(fp_line
			(start -0.7874 -0.4064)
			(end -0.7874 0.4064)
			(stroke
				(width 0.1524)
				(type default)
			)
			(layer "B.SilkS")
		)
		(fp_line
			(start 0.67945 0.3048)
			(end 0.67945 -0.305054)
			(stroke
				(width 0.1)
				(type default)
			)
			(layer "B.Fab")
		)
		(fp_line
			(start 0.67945 -0.305054)
			(end 0.12065 -0.305054)
			(stroke
				(width 0.1)
				(type default)
			)
			(layer "B.Fab")
		)
		(fp_line
			(start 0.12065 0.3048)
			(end 0.67945 0.3048)
			(stroke
				(width 0.1)
				(type default)
			)
			(layer "B.Fab")
		)
		(fp_line
			(start 0.12065 0.2794)
			(end 0.12065 0.3048)
			(stroke
				(width 0.1)
				(type default)
			)
			(layer "B.Fab")
		)
		(fp_line
			(start 0.12065 -0.2794)
			(end -0.12065 -0.2794)
			(stroke
				(width 0.1)
				(type default)
			)
			(layer "B.Fab")
		)
		(fp_line
			(start 0.12065 -0.305054)
			(end 0.12065 -0.2794)
			(stroke
				(width 0.1)
				(type default)
			)
			(layer "B.Fab")
		)
		(fp_line
			(start -0.120396 0.3048)
			(end -0.120396 0.2794)
			(stroke
				(width 0.1)
				(type default)
			)
			(layer "B.Fab")
		)
		(fp_line
			(start -0.120396 0.2794)
			(end 0.12065 0.2794)
			(stroke
				(width 0.1)
				(type default)
			)
			(layer "B.Fab")
		)
		(fp_line
			(start -0.12065 -0.2794)
			(end -0.12065 -0.3048)
			(stroke
				(width 0.1)
				(type default)
			)
			(layer "B.Fab")
		)
		(fp_line
			(start -0.12065 -0.3048)
			(end -0.67945 -0.3048)
			(stroke
				(width 0.1)
				(type default)
			)
			(layer "B.Fab")
		)
		(fp_line
			(start -0.67945 0.3048)
			(end -0.120396 0.3048)
			(stroke
				(width 0.1)
				(type default)
			)
			(layer "B.Fab")
		)
		(fp_line
			(start -0.67945 -0.3048)
			(end -0.67945 0.3048)
			(stroke
				(width 0.1)
				(type default)
			)
			(layer "B.Fab")
		)
		(pad "1" smd rect
			(at 0.40005 0 180)
			(size 0.4572 0.508)
			(layers "B.Cu" "B.Mask" "B.Paste")
			(net "FAN_4_TACH_OL")
		)
		(pad "2" smd rect
			(at -0.40005 0 180)
			(size 0.4572 0.508)
			(layers "B.Cu" "B.Mask" "B.Paste")
			(net "GND")
		)
	)
	(footprint ""
		(layer "B.Cu")
		(at 44.069 -236.924088 180)
		(property "Reference" "C2101"
			(at 0 0 0)
			(layer "B.SilkS")
			(hide yes)
			(effects
				(font
					(size 1.27 1.27)
				)
				(justify mirror)
			)
		)
		(property "Value" ""
			(at 0 0 0)
			(layer "B.Fab")
			(effects
				(font
					(size 1.27 1.27)
				)
				(justify mirror)
			)
		)
		(duplicate_pad_numbers_are_jumpers no)
		(fp_line
			(start 2.2098 0.9398)
			(end 2.2098 -0.9398)
			(stroke
				(width 0.1524)
				(type default)
			)
			(layer "B.SilkS")
		)
		(fp_line
			(start 2.2098 -0.9398)
			(end -2.2098 -0.9398)
			(stroke
				(width 0.1524)
				(type default)
			)
			(layer "B.SilkS")
		)
		(fp_line
			(start -2.2098 0.9398)
			(end 2.2098 0.9398)
			(stroke
				(width 0.1524)
				(type default)
			)
			(layer "B.SilkS")
		)
		(fp_line
			(start -2.2098 -0.9398)
			(end -2.2098 0.9398)
			(stroke
				(width 0.1524)
				(type default)
			)
			(layer "B.SilkS")
		)
		(fp_line
			(start 1.700022 0.899922)
			(end 1.700022 -0.899922)
			(stroke
				(width 0.1)
				(type default)
			)
			(layer "B.Fab")
		)
		(fp_line
			(start 1.700022 -0.899922)
			(end -1.700022 -0.899922)
			(stroke
				(width 0.1)
				(type default)
			)
			(layer "B.Fab")
		)
		(fp_line
			(start -1.700022 0.899922)
			(end 1.700022 0.899922)
			(stroke
				(width 0.1)
				(type default)
			)
			(layer "B.Fab")
		)
		(fp_line
			(start -1.700022 -0.899922)
			(end -1.700022 0.899922)
			(stroke
				(width 0.1)
				(type default)
			)
			(layer "B.Fab")
		)
		(pad "1" smd rect
			(at 1.4732 0 180)
			(size 1.1684 1.5748)
			(layers "B.Cu" "B.Mask" "B.Paste")
			(net "P52V_FAN_1")
		)
		(pad "2" smd rect
			(at -1.4732 0 180)
			(size 1.1684 1.5748)
			(layers "B.Cu" "B.Mask" "B.Paste")
			(net "GND")
		)
	)
	(footprint ""
		(layer "B.Cu")
		(at 17.287494 -73.971912 90)
		(property "Reference" "PC46"
			(at 0 0 90)
			(layer "B.SilkS")
			(hide yes)
			(effects
				(font
					(size 1.27 1.27)
				)
				(justify mirror)
			)
		)
		(property "Value" ""
			(at 0 0 90)
			(layer "B.Fab")
			(effects
				(font
					(size 1.27 1.27)
				)
				(justify mirror)
			)
		)
		(duplicate_pad_numbers_are_jumpers no)
		(fp_line
			(start 0.7874 -0.4064)
			(end -0.7874 -0.4064)
			(stroke
				(width 0.1524)
				(type default)
			)
			(layer "B.SilkS")
		)
		(fp_line
			(start -0.7874 -0.4064)
			(end -0.7874 0.4064)
			(stroke
				(width 0.1524)
				(type default)
			)
			(layer "B.SilkS")
		)
		(fp_line
			(start 0.7874 0.4064)
			(end 0.7874 -0.4064)
			(stroke
				(width 0.1524)
				(type default)
			)
			(layer "B.SilkS")
		)
		(fp_line
			(start -0.7874 0.4064)
			(end 0.7874 0.4064)
			(stroke
				(width 0.1524)
				(type default)
			)
			(layer "B.SilkS")
		)
		(fp_line
			(start 0.67945 -0.305054)
			(end 0.12065 -0.305054)
			(stroke
				(width 0.1)
				(type default)
			)
			(layer "B.Fab")
		)
		(fp_line
			(start 0.12065 -0.305054)
			(end 0.12065 -0.2794)
			(stroke
				(width 0.1)
				(type default)
			)
			(layer "B.Fab")
		)
		(fp_line
			(start -0.12065 -0.3048)
			(end -0.67945 -0.3048)
			(stroke
				(width 0.1)
				(type default)
			)
			(layer "B.Fab")
		)
		(fp_line
			(start -0.67945 -0.3048)
			(end -0.67945 0.3048)
			(stroke
				(width 0.1)
				(type default)
			)
			(layer "B.Fab")
		)
		(fp_line
			(start 0.12065 -0.2794)
			(end -0.12065 -0.2794)
			(stroke
				(width 0.1)
				(type default)
			)
			(layer "B.Fab")
		)
		(fp_line
			(start -0.12065 -0.2794)
			(end -0.12065 -0.3048)
			(stroke
				(width 0.1)
				(type default)
			)
			(layer "B.Fab")
		)
		(fp_line
			(start 0.12065 0.2794)
			(end 0.12065 0.3048)
			(stroke
				(width 0.1)
				(type default)
			)
			(layer "B.Fab")
		)
		(fp_line
			(start -0.120396 0.2794)
			(end 0.12065 0.2794)
			(stroke
				(width 0.1)
				(type default)
			)
			(layer "B.Fab")
		)
		(fp_line
			(start 0.67945 0.3048)
			(end 0.67945 -0.305054)
			(stroke
				(width 0.1)
				(type default)
			)
			(layer "B.Fab")
		)
		(fp_line
			(start 0.12065 0.3048)
			(end 0.67945 0.3048)
			(stroke
				(width 0.1)
				(type default)
			)
			(layer "B.Fab")
		)
		(fp_line
			(start -0.120396 0.3048)
			(end -0.120396 0.2794)
			(stroke
				(width 0.1)
				(type default)
			)
			(layer "B.Fab")
		)
		(fp_line
			(start -0.67945 0.3048)
			(end -0.120396 0.3048)
			(stroke
				(width 0.1)
				(type default)
			)
			(layer "B.Fab")
		)
		(pad "1" smd circle
			(at 0.40005 0 270)
			(size 0 0)
			(layers "B.Cu" "B.Mask" "B.Paste")
			(net "FAN_5_SS")
		)
		(pad "2" smd circle
			(at -0.40005 0 270)
			(size 0 0)
			(layers "B.Cu" "B.Mask" "B.Paste")
			(net "GND")
		)
	)
	(footprint ""
		(layer "B.Cu")
		(at 11.715242 -258.562856 90)
		(property "Reference" "PC57"
			(at 0 0 90)
			(layer "B.SilkS")
			(hide yes)
			(effects
				(font
					(size 1.27 1.27)
				)
				(justify mirror)
			)
		)
		(property "Value" ""
			(at 0 0 90)
			(layer "B.Fab")
			(effects
				(font
					(size 1.27 1.27)
				)
				(justify mirror)
			)
		)
		(duplicate_pad_numbers_are_jumpers no)
		(fp_line
			(start 0.7874 -0.4064)
			(end -0.7874 -0.4064)
			(stroke
				(width 0.1524)
				(type default)
			)
			(layer "B.SilkS")
		)
		(fp_line
			(start -0.7874 -0.4064)
			(end -0.7874 0.4064)
			(stroke
				(width 0.1524)
				(type default)
			)
			(layer "B.SilkS")
		)
		(fp_line
			(start 0.7874 0.4064)
			(end 0.7874 -0.4064)
			(stroke
				(width 0.1524)
				(type default)
			)
			(layer "B.SilkS")
		)
		(fp_line
			(start -0.7874 0.4064)
			(end 0.7874 0.4064)
			(stroke
				(width 0.1524)
				(type default)
			)
			(layer "B.SilkS")
		)
		(fp_line
			(start 0.67945 -0.305054)
			(end 0.12065 -0.305054)
			(stroke
				(width 0.1)
				(type default)
			)
			(layer "B.Fab")
		)
		(fp_line
			(start 0.12065 -0.305054)
			(end 0.12065 -0.2794)
			(stroke
				(width 0.1)
				(type default)
			)
			(layer "B.Fab")
		)
		(fp_line
			(start -0.12065 -0.3048)
			(end -0.67945 -0.3048)
			(stroke
				(width 0.1)
				(type default)
			)
			(layer "B.Fab")
		)
		(fp_line
			(start -0.67945 -0.3048)
			(end -0.67945 0.3048)
			(stroke
				(width 0.1)
				(type default)
			)
			(layer "B.Fab")
		)
		(fp_line
			(start 0.12065 -0.2794)
			(end -0.12065 -0.2794)
			(stroke
				(width 0.1)
				(type default)
			)
			(layer "B.Fab")
		)
		(fp_line
			(start -0.12065 -0.2794)
			(end -0.12065 -0.3048)
			(stroke
				(width 0.1)
				(type default)
			)
			(layer "B.Fab")
		)
		(fp_line
			(start 0.12065 0.2794)
			(end 0.12065 0.3048)
			(stroke
				(width 0.1)
				(type default)
			)
			(layer "B.Fab")
		)
		(fp_line
			(start -0.120396 0.2794)
			(end 0.12065 0.2794)
			(stroke
				(width 0.1)
				(type default)
			)
			(layer "B.Fab")
		)
		(fp_line
			(start 0.67945 0.3048)
			(end 0.67945 -0.305054)
			(stroke
				(width 0.1)
				(type default)
			)
			(layer "B.Fab")
		)
		(fp_line
			(start 0.12065 0.3048)
			(end 0.67945 0.3048)
			(stroke
				(width 0.1)
				(type default)
			)
			(layer "B.Fab")
		)
		(fp_line
			(start -0.120396 0.3048)
			(end -0.120396 0.2794)
			(stroke
				(width 0.1)
				(type default)
			)
			(layer "B.Fab")
		)
		(fp_line
			(start -0.67945 0.3048)
			(end -0.120396 0.3048)
			(stroke
				(width 0.1)
				(type default)
			)
			(layer "B.Fab")
		)
		(pad "1" smd circle
			(at 0.40005 0 270)
			(size 0 0)
			(layers "B.Cu" "B.Mask" "B.Paste")
			(net "FAN_7_P5V")
		)
		(pad "2" smd circle
			(at -0.40005 0 270)
			(size 0 0)
			(layers "B.Cu" "B.Mask" "B.Paste")
			(net "GND")
		)
	)
	(footprint ""
		(layer "B.Cu")
		(at 40.894 -128.905 180)
		(property "Reference" "R5432"
			(at 0 0 0)
			(layer "B.SilkS")
			(hide yes)
			(effects
				(font
					(size 1.27 1.27)
				)
				(justify mirror)
			)
		)
		(property "Value" ""
			(at 0 0 0)
			(layer "B.Fab")
			(effects
				(font
					(size 1.27 1.27)
				)
				(justify mirror)
			)
		)
		(duplicate_pad_numbers_are_jumpers no)
		(fp_line
			(start 0.7874 0.4064)
			(end 0.7874 -0.4064)
			(stroke
				(width 0.1524)
				(type default)
			)
			(layer "B.SilkS")
		)
		(fp_line
			(start 0.7874 -0.4064)
			(end -0.7874 -0.4064)
			(stroke
				(width 0.1524)
				(type default)
			)
			(layer "B.SilkS")
		)
		(fp_line
			(start -0.7874 0.4064)
			(end 0.7874 0.4064)
			(stroke
				(width 0.1524)
				(type default)
			)
			(layer "B.SilkS")
		)
		(fp_line
			(start -0.7874 -0.4064)
			(end -0.7874 0.4064)
			(stroke
				(width 0.1524)
				(type default)
			)
			(layer "B.SilkS")
		)
		(fp_line
			(start 0.67945 0.3048)
			(end 0.67945 -0.305054)
			(stroke
				(width 0.1)
				(type default)
			)
			(layer "B.Fab")
		)
		(fp_line
			(start 0.67945 -0.305054)
			(end 0.12065 -0.305054)
			(stroke
				(width 0.1)
				(type default)
			)
			(layer "B.Fab")
		)
		(fp_line
			(start 0.12065 0.3048)
			(end 0.67945 0.3048)
			(stroke
				(width 0.1)
				(type default)
			)
			(layer "B.Fab")
		)
		(fp_line
			(start 0.12065 0.2794)
			(end 0.12065 0.3048)
			(stroke
				(width 0.1)
				(type default)
			)
			(layer "B.Fab")
		)
		(fp_line
			(start 0.12065 -0.2794)
			(end -0.12065 -0.2794)
			(stroke
				(width 0.1)
				(type default)
			)
			(layer "B.Fab")
		)
		(fp_line
			(start 0.12065 -0.305054)
			(end 0.12065 -0.2794)
			(stroke
				(width 0.1)
				(type default)
			)
			(layer "B.Fab")
		)
		(fp_line
			(start -0.120396 0.3048)
			(end -0.120396 0.2794)
			(stroke
				(width 0.1)
				(type default)
			)
			(layer "B.Fab")
		)
		(fp_line
			(start -0.120396 0.2794)
			(end 0.12065 0.2794)
			(stroke
				(width 0.1)
				(type default)
			)
			(layer "B.Fab")
		)
		(fp_line
			(start -0.12065 -0.2794)
			(end -0.12065 -0.3048)
			(stroke
				(width 0.1)
				(type default)
			)
			(layer "B.Fab")
		)
		(fp_line
			(start -0.12065 -0.3048)
			(end -0.67945 -0.3048)
			(stroke
				(width 0.1)
				(type default)
			)
			(layer "B.Fab")
		)
		(fp_line
			(start -0.67945 0.3048)
			(end -0.120396 0.3048)
			(stroke
				(width 0.1)
				(type default)
			)
			(layer "B.Fab")
		)
		(fp_line
			(start -0.67945 -0.3048)
			(end -0.67945 0.3048)
			(stroke
				(width 0.1)
				(type default)
			)
			(layer "B.Fab")
		)
		(pad "1" smd rect
			(at 0.40005 0 180)
			(size 0.4572 0.508)
			(layers "B.Cu" "B.Mask" "B.Paste")
			(net "FAN_3_TACH_IL")
		)
		(pad "2" smd rect
			(at -0.40005 0 180)
			(size 0.4572 0.508)
			(layers "B.Cu" "B.Mask" "B.Paste")
			(net "GND")
		)
	)
	(footprint ""
		(layer "B.Cu")
		(at 34.163 -271.526)
		(property "Reference" "PC1"
			(at 0 0 0)
			(layer "B.SilkS")
			(hide yes)
			(effects
				(font
					(size 1.27 1.27)
				)
				(justify mirror)
			)
		)
		(property "Value" ""
			(at 0 0 0)
			(layer "B.Fab")
			(effects
				(font
					(size 1.27 1.27)
				)
				(justify mirror)
			)
		)
		(duplicate_pad_numbers_are_jumpers no)
		(fp_line
			(start -1.524 -0.762)
			(end -1.524 0.762)
			(stroke
				(width 0.1524)
				(type default)
			)
			(layer "B.SilkS")
		)
		(fp_line
			(start -1.524 0.762)
			(end 1.524 0.762)
			(stroke
				(width 0.1524)
				(type default)
			)
			(layer "B.SilkS")
		)
		(fp_line
			(start 1.524 -0.762)
			(end -1.524 -0.762)
			(stroke
				(width 0.1524)
				(type default)
			)
			(layer "B.SilkS")
		)
		(fp_line
			(start 1.524 0.762)
			(end 1.524 -0.762)
			(stroke
				(width 0.1524)
				(type default)
			)
			(layer "B.SilkS")
		)
		(fp_line
			(start -1.1049 -0.724916)
			(end 1.1049 -0.724916)
			(stroke
				(width 0.1)
				(type default)
			)
			(layer "B.Fab")
		)
		(fp_line
			(start -1.1049 0.724916)
			(end -1.1049 -0.724916)
			(stroke
				(width 0.1)
				(type default)
			)
			(layer "B.Fab")
		)
		(fp_line
			(start 1.1049 -0.724916)
			(end 1.1049 0.724916)
			(stroke
				(width 0.1)
				(type default)
			)
			(layer "B.Fab")
		)
		(fp_line
			(start 1.1049 0.724916)
			(end -1.1049 0.724916)
			(stroke
				(width 0.1)
				(type default)
			)
			(layer "B.Fab")
		)
		(pad "1" smd rect
			(at 0.889 0)
			(size 1.016 1.27)
			(layers "B.Cu" "B.Mask" "B.Paste")
			(net "P52V_FAN_0")
		)
		(pad "2" smd rect
			(at -0.889 0)
			(size 1.016 1.27)
			(layers "B.Cu" "B.Mask" "B.Paste")
			(net "GND")
		)
	)
)
